(kicad_pcb
	(version 20260206)
	(generator "pcbnew")
	(generator_version "10.0")
	(general
		(thickness 1.6)
		(legacy_teardrops no)
	)
	(paper "A4")
	(title_block
		(title "04192023_DAF0TMB3IC0_F0TG_MB_C_brd_V02_OCP.brd")
		(comment 1 "Grand Teton / footprint 583 of 8354 (J27), pads 114-226 of 291")
	)
	(layers
		(0 "F.Cu" signal "TOP")
		(4 "In1.Cu" signal "GND")
		(6 "In2.Cu" signal "IN1")
		(8 "In3.Cu" signal "GND1")
		(10 "In4.Cu" signal "IN2")
		(12 "In5.Cu" signal "GND2")
		(14 "In6.Cu" signal "IN3")
		(16 "In7.Cu" signal "GND3")
		(18 "In8.Cu" signal "VCC")
		(20 "In9.Cu" signal "VCC1")
		(22 "In10.Cu" signal "GND4")
		(24 "In11.Cu" signal "IN4")
		(26 "In12.Cu" signal "GND5")
		(28 "In13.Cu" signal "IN5")
		(30 "In14.Cu" signal "GND6")
		(32 "In15.Cu" signal "IN6")
		(34 "In16.Cu" signal "GND7")
		(2 "B.Cu" signal "BOTTOM")
		(9 "F.Adhes" user "F.Adhesive")
		(11 "B.Adhes" user "B.Adhesive")
		(13 "F.Paste" user "Package Geometry/Pastemask Top")
		(15 "B.Paste" user "Package Geometry/Pastemask Bottom")
		(5 "F.SilkS" user "Ref Des/Silkscreen Top")
		(7 "B.SilkS" user "Ref Des/Silkscreen Bottom")
		(1 "F.Mask" user "Board Geometry/Soldermask Top")
		(3 "B.Mask" user "Board Geometry/Soldermask Bottom")
		(17 "Dwgs.User" user "User.Drawings")
		(19 "Cmts.User" user "User.Comments")
		(21 "Eco1.User" user "User.Eco1")
		(23 "Eco2.User" user "User.Eco2")
		(25 "Edge.Cuts" user "Board Geometry/Outline")
		(27 "Margin" user)
		(31 "F.CrtYd" user "Package Geometry/Place Bound Top")
		(29 "B.CrtYd" user "Package Geometry/Place Bound Bottom")
		(35 "F.Fab" user "Ref Des/Assembly Top")
		(33 "B.Fab" user "Ref Des/Assembly Bottom")
	)
	(footprint ""
		(layer "F.Cu")
		(at 174.022004 -255.560322 180)
		(property "Reference" "J27"
			(at -2.7178 -81.857088 0)
			(unlocked yes)
			(layer "F.SilkS")
			(effects
				(font
					(size 0.7874 0.5842)
					(thickness 0.1524)
				)
			)
		)
		(property "Value" ""
			(at 0 0 180)
			(layer "F.Fab")
			(effects
				(font
					(size 1.27 1.27)
				)
			)
		)
		(duplicate_pad_numbers_are_jumpers no)
		(pad "114" smd rect
			(at -2.050034 37.824918 90)
			(size 0.519938 1.4986)
			(layers "F.Cu" "F.Mask" "F.Paste")
			(net "GND")
		)
		(pad "115" smd rect
			(at -2.050034 38.675056 90)
			(size 0.519938 1.4986)
			(layers "F.Cu" "F.Mask" "F.Paste")
			(net "M_H_CPU1_SB_DQS_DP<1>")
		)
		(pad "116" smd rect
			(at -2.050034 39.52494 90)
			(size 0.519938 1.4986)
			(layers "F.Cu" "F.Mask" "F.Paste")
			(net "M_H_CPU1_SB_DQS_DN<1>")
		)
		(pad "117" smd rect
			(at -2.050034 40.375078 90)
			(size 0.519938 1.4986)
			(layers "F.Cu" "F.Mask" "F.Paste")
			(net "GND")
		)
		(pad "118" smd rect
			(at -2.050034 41.224962 90)
			(size 0.519938 1.4986)
			(layers "F.Cu" "F.Mask" "F.Paste")
			(net "M_H_CPU1_SB_DQ<12>")
		)
		(pad "119" smd rect
			(at -2.050034 42.0751 90)
			(size 0.519938 1.4986)
			(layers "F.Cu" "F.Mask" "F.Paste")
			(net "GND")
		)
		(pad "120" smd rect
			(at -2.050034 42.924984 90)
			(size 0.519938 1.4986)
			(layers "F.Cu" "F.Mask" "F.Paste")
			(net "M_H_CPU1_SB_DQ<13>")
		)
		(pad "121" smd rect
			(at -2.050034 43.775122 90)
			(size 0.519938 1.4986)
			(layers "F.Cu" "F.Mask" "F.Paste")
			(net "GND")
		)
		(pad "122" smd rect
			(at -2.050034 44.625006 90)
			(size 0.519938 1.4986)
			(layers "F.Cu" "F.Mask" "F.Paste")
			(net "M_H_CPU1_SB_DQ<16>")
		)
		(pad "123" smd rect
			(at -2.050034 45.47489 90)
			(size 0.519938 1.4986)
			(layers "F.Cu" "F.Mask" "F.Paste")
			(net "GND")
		)
		(pad "124" smd rect
			(at -2.050034 46.325028 90)
			(size 0.519938 1.4986)
			(layers "F.Cu" "F.Mask" "F.Paste")
			(net "M_H_CPU1_SB_DQ<17>")
		)
		(pad "125" smd rect
			(at -2.050034 47.174912 90)
			(size 0.519938 1.4986)
			(layers "F.Cu" "F.Mask" "F.Paste")
			(net "GND")
		)
		(pad "126" smd rect
			(at -2.050034 48.02505 90)
			(size 0.519938 1.4986)
			(layers "F.Cu" "F.Mask" "F.Paste")
			(net "M_H_CPU1_SB_DQS_DP<2>")
		)
		(pad "127" smd rect
			(at -2.050034 48.874934 90)
			(size 0.519938 1.4986)
			(layers "F.Cu" "F.Mask" "F.Paste")
			(net "M_H_CPU1_SB_DQS_DN<2>")
		)
		(pad "128" smd rect
			(at -2.050034 49.725072 90)
			(size 0.519938 1.4986)
			(layers "F.Cu" "F.Mask" "F.Paste")
			(net "GND")
		)
		(pad "129" smd rect
			(at -2.050034 50.574956 90)
			(size 0.519938 1.4986)
			(layers "F.Cu" "F.Mask" "F.Paste")
			(net "M_H_CPU1_SB_DQ<20>")
		)
		(pad "130" smd rect
			(at -2.050034 51.425094 90)
			(size 0.519938 1.4986)
			(layers "F.Cu" "F.Mask" "F.Paste")
			(net "GND")
		)
		(pad "131" smd rect
			(at -2.050034 52.274978 90)
			(size 0.519938 1.4986)
			(layers "F.Cu" "F.Mask" "F.Paste")
			(net "M_H_CPU1_SB_DQ<21>")
		)
		(pad "132" smd rect
			(at -2.050034 53.125116 90)
			(size 0.519938 1.4986)
			(layers "F.Cu" "F.Mask" "F.Paste")
			(net "GND")
		)
		(pad "133" smd rect
			(at -2.050034 53.975 90)
			(size 0.519938 1.4986)
			(layers "F.Cu" "F.Mask" "F.Paste")
			(net "M_H_CPU1_SB_DQ<24>")
		)
		(pad "134" smd rect
			(at -2.050034 54.824884 90)
			(size 0.519938 1.4986)
			(layers "F.Cu" "F.Mask" "F.Paste")
			(net "GND")
		)
		(pad "135" smd rect
			(at -2.050034 55.675022 90)
			(size 0.519938 1.4986)
			(layers "F.Cu" "F.Mask" "F.Paste")
			(net "M_H_CPU1_SB_DQ<25>")
		)
		(pad "136" smd rect
			(at -2.050034 56.524906 90)
			(size 0.519938 1.4986)
			(layers "F.Cu" "F.Mask" "F.Paste")
			(net "GND")
		)
		(pad "137" smd rect
			(at -2.050034 57.375044 90)
			(size 0.519938 1.4986)
			(layers "F.Cu" "F.Mask" "F.Paste")
			(net "M_H_CPU1_SB_DQS_DP<3>")
		)
		(pad "138" smd rect
			(at -2.050034 58.224928 90)
			(size 0.519938 1.4986)
			(layers "F.Cu" "F.Mask" "F.Paste")
			(net "M_H_CPU1_SB_DQS_DN<3>")
		)
		(pad "139" smd rect
			(at -2.050034 59.075066 90)
			(size 0.519938 1.4986)
			(layers "F.Cu" "F.Mask" "F.Paste")
			(net "GND")
		)
		(pad "140" smd rect
			(at -2.050034 59.92495 90)
			(size 0.519938 1.4986)
			(layers "F.Cu" "F.Mask" "F.Paste")
			(net "M_H_CPU1_SB_DQ<28>")
		)
		(pad "141" smd rect
			(at -2.050034 60.775088 90)
			(size 0.519938 1.4986)
			(layers "F.Cu" "F.Mask" "F.Paste")
			(net "GND")
		)
		(pad "142" smd rect
			(at -2.050034 61.624972 90)
			(size 0.519938 1.4986)
			(layers "F.Cu" "F.Mask" "F.Paste")
			(net "M_H_CPU1_SB_DQ<29>")
		)
		(pad "143" smd rect
			(at -2.050034 62.47511 90)
			(size 0.519938 1.4986)
			(layers "F.Cu" "F.Mask" "F.Paste")
			(net "GND")
		)
		(pad "144" smd rect
			(at -2.050034 63.324994 90)
			(size 0.519938 1.4986)
			(layers "F.Cu" "F.Mask" "F.Paste")
			(net "Net_2355")
		)
		(pad "145" smd rect
			(at 2.050034 -63.324994 90)
			(size 0.519938 1.4986)
			(layers "F.Cu" "F.Mask" "F.Paste")
			(net "P12V_MEM_CPU1")
		)
		(pad "146" smd rect
			(at 2.050034 -62.47511 90)
			(size 0.519938 1.4986)
			(layers "F.Cu" "F.Mask" "F.Paste")
			(net "P12V_MEM_CPU1")
		)
		(pad "147" smd rect
			(at 2.050034 -61.624972 90)
			(size 0.519938 1.4986)
			(layers "F.Cu" "F.Mask" "F.Paste")
			(net "PWRGD_CHH_CPU1_DIMM")
		)
		(pad "148" smd rect
			(at 2.050034 -60.775088 90)
			(size 0.519938 1.4986)
			(layers "F.Cu" "F.Mask" "F.Paste")
			(net "PD_CHH_CPU1_DIMM_SAA")
		)
		(pad "149" smd rect
			(at 2.050034 -59.92495 90)
			(size 0.519938 1.4986)
			(layers "F.Cu" "F.Mask" "F.Paste")
			(net "Net_2356")
		)
		(pad "150" smd rect
			(at 2.050034 -59.075066 90)
			(size 0.519938 1.4986)
			(layers "F.Cu" "F.Mask" "F.Paste")
			(net "Net_2357")
		)
		(pad "151" smd rect
			(at 2.050034 -58.224928 90)
			(size 0.519938 1.4986)
			(layers "F.Cu" "F.Mask" "F.Paste")
			(net "GND")
		)
		(pad "152" smd rect
			(at 2.050034 -57.375044 90)
			(size 0.519938 1.4986)
			(layers "F.Cu" "F.Mask" "F.Paste")
			(net "M_H_CPU1_SA_DQ<2>")
		)
		(pad "153" smd rect
			(at 2.050034 -56.524906 90)
			(size 0.519938 1.4986)
			(layers "F.Cu" "F.Mask" "F.Paste")
			(net "GND")
		)
		(pad "154" smd rect
			(at 2.050034 -55.675022 90)
			(size 0.519938 1.4986)
			(layers "F.Cu" "F.Mask" "F.Paste")
			(net "M_H_CPU1_SA_DQ<3>")
		)
		(pad "155" smd rect
			(at 2.050034 -54.824884 90)
			(size 0.519938 1.4986)
			(layers "F.Cu" "F.Mask" "F.Paste")
			(net "GND")
		)
		(pad "156" smd rect
			(at 2.050034 -53.975 90)
			(size 0.519938 1.4986)
			(layers "F.Cu" "F.Mask" "F.Paste")
			(net "M_H_CPU1_SA_DQS_DN<5>")
		)
		(pad "157" smd rect
			(at 2.050034 -53.125116 90)
			(size 0.519938 1.4986)
			(layers "F.Cu" "F.Mask" "F.Paste")
			(net "M_H_CPU1_SA_DQS_DP<5>")
		)
		(pad "158" smd rect
			(at 2.050034 -52.274978 90)
			(size 0.519938 1.4986)
			(layers "F.Cu" "F.Mask" "F.Paste")
			(net "GND")
		)
		(pad "159" smd rect
			(at 2.050034 -51.425094 90)
			(size 0.519938 1.4986)
			(layers "F.Cu" "F.Mask" "F.Paste")
			(net "M_H_CPU1_SA_DQ<6>")
		)
		(pad "160" smd rect
			(at 2.050034 -50.574956 90)
			(size 0.519938 1.4986)
			(layers "F.Cu" "F.Mask" "F.Paste")
			(net "GND")
		)
		(pad "161" smd rect
			(at 2.050034 -49.725072 90)
			(size 0.519938 1.4986)
			(layers "F.Cu" "F.Mask" "F.Paste")
			(net "M_H_CPU1_SA_DQ<7>")
		)
		(pad "162" smd rect
			(at 2.050034 -48.874934 90)
			(size 0.519938 1.4986)
			(layers "F.Cu" "F.Mask" "F.Paste")
			(net "GND")
		)
		(pad "163" smd rect
			(at 2.050034 -48.02505 90)
			(size 0.519938 1.4986)
			(layers "F.Cu" "F.Mask" "F.Paste")
			(net "M_H_CPU1_SA_DQ<10>")
		)
		(pad "164" smd rect
			(at 2.050034 -47.174912 90)
			(size 0.519938 1.4986)
			(layers "F.Cu" "F.Mask" "F.Paste")
			(net "GND")
		)
		(pad "165" smd rect
			(at 2.050034 -46.325028 90)
			(size 0.519938 1.4986)
			(layers "F.Cu" "F.Mask" "F.Paste")
			(net "M_H_CPU1_SA_DQ<11>")
		)
		(pad "166" smd rect
			(at 2.050034 -45.47489 90)
			(size 0.519938 1.4986)
			(layers "F.Cu" "F.Mask" "F.Paste")
			(net "GND")
		)
		(pad "167" smd rect
			(at 2.050034 -44.625006 90)
			(size 0.519938 1.4986)
			(layers "F.Cu" "F.Mask" "F.Paste")
			(net "M_H_CPU1_SA_DQS_DN<6>")
		)
		(pad "168" smd rect
			(at 2.050034 -43.775122 90)
			(size 0.519938 1.4986)
			(layers "F.Cu" "F.Mask" "F.Paste")
			(net "M_H_CPU1_SA_DQS_DP<6>")
		)
		(pad "169" smd rect
			(at 2.050034 -42.924984 90)
			(size 0.519938 1.4986)
			(layers "F.Cu" "F.Mask" "F.Paste")
			(net "GND")
		)
		(pad "170" smd rect
			(at 2.050034 -42.0751 90)
			(size 0.519938 1.4986)
			(layers "F.Cu" "F.Mask" "F.Paste")
			(net "M_H_CPU1_SA_DQ<14>")
		)
		(pad "171" smd rect
			(at 2.050034 -41.224962 90)
			(size 0.519938 1.4986)
			(layers "F.Cu" "F.Mask" "F.Paste")
			(net "GND")
		)
		(pad "172" smd rect
			(at 2.050034 -40.375078 90)
			(size 0.519938 1.4986)
			(layers "F.Cu" "F.Mask" "F.Paste")
			(net "M_H_CPU1_SA_DQ<15>")
		)
		(pad "173" smd rect
			(at 2.050034 -39.52494 90)
			(size 0.519938 1.4986)
			(layers "F.Cu" "F.Mask" "F.Paste")
			(net "GND")
		)
		(pad "174" smd rect
			(at 2.050034 -38.675056 90)
			(size 0.519938 1.4986)
			(layers "F.Cu" "F.Mask" "F.Paste")
			(net "M_H_CPU1_SA_DQ<18>")
		)
		(pad "175" smd rect
			(at 2.050034 -37.824918 90)
			(size 0.519938 1.4986)
			(layers "F.Cu" "F.Mask" "F.Paste")
			(net "GND")
		)
		(pad "176" smd rect
			(at 2.050034 -36.975034 90)
			(size 0.519938 1.4986)
			(layers "F.Cu" "F.Mask" "F.Paste")
			(net "M_H_CPU1_SA_DQ<19>")
		)
		(pad "177" smd rect
			(at 2.050034 -36.124896 90)
			(size 0.519938 1.4986)
			(layers "F.Cu" "F.Mask" "F.Paste")
			(net "GND")
		)
		(pad "178" smd rect
			(at 2.050034 -35.275012 90)
			(size 0.519938 1.4986)
			(layers "F.Cu" "F.Mask" "F.Paste")
			(net "M_H_CPU1_SA_DQS_DN<7>")
		)
		(pad "179" smd rect
			(at 2.050034 -34.425128 90)
			(size 0.519938 1.4986)
			(layers "F.Cu" "F.Mask" "F.Paste")
			(net "M_H_CPU1_SA_DQS_DP<7>")
		)
		(pad "180" smd rect
			(at 2.050034 -33.57499 90)
			(size 0.519938 1.4986)
			(layers "F.Cu" "F.Mask" "F.Paste")
			(net "GND")
		)
		(pad "181" smd rect
			(at 2.050034 -32.725106 90)
			(size 0.519938 1.4986)
			(layers "F.Cu" "F.Mask" "F.Paste")
			(net "M_H_CPU1_SA_DQ<22>")
		)
		(pad "182" smd rect
			(at 2.050034 -31.874968 90)
			(size 0.519938 1.4986)
			(layers "F.Cu" "F.Mask" "F.Paste")
			(net "GND")
		)
		(pad "183" smd rect
			(at 2.050034 -31.025084 90)
			(size 0.519938 1.4986)
			(layers "F.Cu" "F.Mask" "F.Paste")
			(net "M_H_CPU1_SA_DQ<23>")
		)
		(pad "184" smd rect
			(at 2.050034 -30.174946 90)
			(size 0.519938 1.4986)
			(layers "F.Cu" "F.Mask" "F.Paste")
			(net "GND")
		)
		(pad "185" smd rect
			(at 2.050034 -29.325062 90)
			(size 0.519938 1.4986)
			(layers "F.Cu" "F.Mask" "F.Paste")
			(net "M_H_CPU1_SA_DQ<26>")
		)
		(pad "186" smd rect
			(at 2.050034 -28.474924 90)
			(size 0.519938 1.4986)
			(layers "F.Cu" "F.Mask" "F.Paste")
			(net "GND")
		)
		(pad "187" smd rect
			(at 2.050034 -27.62504 90)
			(size 0.519938 1.4986)
			(layers "F.Cu" "F.Mask" "F.Paste")
			(net "M_H_CPU1_SA_DQ<27>")
		)
		(pad "188" smd rect
			(at 2.050034 -26.774902 90)
			(size 0.519938 1.4986)
			(layers "F.Cu" "F.Mask" "F.Paste")
			(net "GND")
		)
		(pad "189" smd rect
			(at 2.050034 -25.925018 90)
			(size 0.519938 1.4986)
			(layers "F.Cu" "F.Mask" "F.Paste")
			(net "M_H_CPU1_SA_DQS_DN<8>")
		)
		(pad "190" smd rect
			(at 2.050034 -25.07488 90)
			(size 0.519938 1.4986)
			(layers "F.Cu" "F.Mask" "F.Paste")
			(net "M_H_CPU1_SA_DQS_DP<8>")
		)
		(pad "191" smd rect
			(at 2.050034 -24.224996 90)
			(size 0.519938 1.4986)
			(layers "F.Cu" "F.Mask" "F.Paste")
			(net "GND")
		)
		(pad "192" smd rect
			(at 2.050034 -23.375112 90)
			(size 0.519938 1.4986)
			(layers "F.Cu" "F.Mask" "F.Paste")
			(net "M_H_CPU1_SA_DQ<30>")
		)
		(pad "193" smd rect
			(at 2.050034 -22.524974 90)
			(size 0.519938 1.4986)
			(layers "F.Cu" "F.Mask" "F.Paste")
			(net "GND")
		)
		(pad "194" smd rect
			(at 2.050034 -21.67509 90)
			(size 0.519938 1.4986)
			(layers "F.Cu" "F.Mask" "F.Paste")
			(net "M_H_CPU1_SA_DQ<31>")
		)
		(pad "195" smd rect
			(at 2.050034 -20.824952 90)
			(size 0.519938 1.4986)
			(layers "F.Cu" "F.Mask" "F.Paste")
			(net "GND")
		)
		(pad "196" smd rect
			(at 2.050034 -19.975068 90)
			(size 0.519938 1.4986)
			(layers "F.Cu" "F.Mask" "F.Paste")
			(net "M_H_CPU1_SA_CB<2>")
		)
		(pad "197" smd rect
			(at 2.050034 -19.12493 90)
			(size 0.519938 1.4986)
			(layers "F.Cu" "F.Mask" "F.Paste")
			(net "GND")
		)
		(pad "198" smd rect
			(at 2.050034 -18.275046 90)
			(size 0.519938 1.4986)
			(layers "F.Cu" "F.Mask" "F.Paste")
			(net "M_H_CPU1_SA_CB<3>")
		)
		(pad "199" smd rect
			(at 2.050034 -17.424908 90)
			(size 0.519938 1.4986)
			(layers "F.Cu" "F.Mask" "F.Paste")
			(net "GND")
		)
		(pad "200" smd rect
			(at 2.050034 -16.575024 90)
			(size 0.519938 1.4986)
			(layers "F.Cu" "F.Mask" "F.Paste")
			(net "M_H_CPU1_SA_DQS_DN<9>")
		)
		(pad "201" smd rect
			(at 2.050034 -15.724886 90)
			(size 0.519938 1.4986)
			(layers "F.Cu" "F.Mask" "F.Paste")
			(net "M_H_CPU1_SA_DQS_DP<9>")
		)
		(pad "202" smd rect
			(at 2.050034 -14.875002 90)
			(size 0.519938 1.4986)
			(layers "F.Cu" "F.Mask" "F.Paste")
			(net "GND")
		)
		(pad "203" smd rect
			(at 2.050034 -14.025118 90)
			(size 0.519938 1.4986)
			(layers "F.Cu" "F.Mask" "F.Paste")
			(net "M_H_CPU1_SA_CB<6>")
		)
		(pad "204" smd rect
			(at 2.050034 -13.17498 90)
			(size 0.519938 1.4986)
			(layers "F.Cu" "F.Mask" "F.Paste")
			(net "GND")
		)
		(pad "205" smd rect
			(at 2.050034 -12.325096 90)
			(size 0.519938 1.4986)
			(layers "F.Cu" "F.Mask" "F.Paste")
			(net "M_H_CPU1_SA_CB<7>")
		)
		(pad "206" smd rect
			(at 2.050034 -11.474958 90)
			(size 0.519938 1.4986)
			(layers "F.Cu" "F.Mask" "F.Paste")
			(net "GND")
		)
		(pad "207" smd rect
			(at 2.050034 -10.625074 90)
			(size 0.519938 1.4986)
			(layers "F.Cu" "F.Mask" "F.Paste")
			(net "M_H_CPU1_RESET_N")
		)
		(pad "208" smd rect
			(at 2.050034 -9.774936 90)
			(size 0.519938 1.4986)
			(layers "F.Cu" "F.Mask" "F.Paste")
			(net "GND")
		)
		(pad "209" smd rect
			(at 2.050034 -8.925052 90)
			(size 0.519938 1.4986)
			(layers "F.Cu" "F.Mask" "F.Paste")
			(net "M_H_CPU1_SA_CS_N<1>")
		)
		(pad "210" smd rect
			(at 2.050034 -8.074914 90)
			(size 0.519938 1.4986)
			(layers "F.Cu" "F.Mask" "F.Paste")
			(net "GND")
		)
		(pad "211" smd rect
			(at 2.050034 -7.22503 90)
			(size 0.519938 1.4986)
			(layers "F.Cu" "F.Mask" "F.Paste")
			(net "M_H_CPU1_SA_CA<1>")
		)
		(pad "212" smd rect
			(at 2.050034 -6.374892 90)
			(size 0.519938 1.4986)
			(layers "F.Cu" "F.Mask" "F.Paste")
			(net "GND")
		)
		(pad "213" smd rect
			(at 2.050034 -5.525008 90)
			(size 0.519938 1.4986)
			(layers "F.Cu" "F.Mask" "F.Paste")
			(net "M_H_CPU1_SA_CA<3>")
		)
		(pad "214" smd rect
			(at 2.050034 -4.675124 90)
			(size 0.519938 1.4986)
			(layers "F.Cu" "F.Mask" "F.Paste")
			(net "GND")
		)
		(pad "215" smd rect
			(at 2.050034 -3.824986 90)
			(size 0.519938 1.4986)
			(layers "F.Cu" "F.Mask" "F.Paste")
			(net "M_H_CPU1_SA_CA<5>")
		)
		(pad "216" smd rect
			(at 2.050034 -2.975102 90)
			(size 0.519938 1.4986)
			(layers "F.Cu" "F.Mask" "F.Paste")
			(net "GND")
		)
		(pad "217" smd rect
			(at 2.050034 -2.124964 90)
			(size 0.519938 1.4986)
			(layers "F.Cu" "F.Mask" "F.Paste")
			(net "M_H_CPU1_CLK_DP<0>")
		)
		(pad "218" smd rect
			(at 2.050034 -1.27508 90)
			(size 0.519938 1.4986)
			(layers "F.Cu" "F.Mask" "F.Paste")
			(net "M_H_CPU1_CLK_DN<0>")
		)
		(pad "219" smd rect
			(at 2.050034 -0.424942 90)
			(size 0.519938 1.4986)
			(layers "F.Cu" "F.Mask" "F.Paste")
			(net "GND")
		)
		(pad "220" smd rect
			(at 2.050034 5.525008 90)
			(size 0.519938 1.4986)
			(layers "F.Cu" "F.Mask" "F.Paste")
			(net "Net_2358")
		)
		(pad "221" smd rect
			(at 2.050034 6.374892 90)
			(size 0.519938 1.4986)
			(layers "F.Cu" "F.Mask" "F.Paste")
			(net "M_H_CPU1_SB_CA<1>")
		)
		(pad "222" smd rect
			(at 2.050034 7.22503 90)
			(size 0.519938 1.4986)
			(layers "F.Cu" "F.Mask" "F.Paste")
			(net "GND")
		)
		(pad "223" smd rect
			(at 2.050034 8.074914 90)
			(size 0.519938 1.4986)
			(layers "F.Cu" "F.Mask" "F.Paste")
			(net "M_H_CPU1_SB_CA<3>")
		)
		(pad "224" smd rect
			(at 2.050034 8.925052 90)
			(size 0.519938 1.4986)
			(layers "F.Cu" "F.Mask" "F.Paste")
			(net "GND")
		)
		(pad "225" smd rect
			(at 2.050034 9.774936 90)
			(size 0.519938 1.4986)
			(layers "F.Cu" "F.Mask" "F.Paste")
			(net "M_H_CPU1_SB_CA<5>")
		)
		(pad "226" smd rect
			(at 2.050034 10.625074 90)
			(size 0.519938 1.4986)
			(layers "F.Cu" "F.Mask" "F.Paste")
			(net "GND")
		)
	)
)
